(kicad_pcb
	(version 20260206)
	(generator "pcbnew")
	(generator_version "10.0")
	(general
		(thickness 1.6)
		(legacy_teardrops no)
	)
	(paper "A4")
	(title_block
		(title "Wiwynn_Tioga_Pass_MB.brd")
		(comment 1 "Tioga Pass / footprints 3631-3637 of 4770")
	)
	(layers
		(0 "F.Cu" signal "TOP")
		(4 "In1.Cu" signal "L2GND")
		(6 "In2.Cu" signal "L3")
		(8 "In3.Cu" signal "L4GND")
		(10 "In4.Cu" signal "L5")
		(12 "In5.Cu" signal "L6GND")
		(14 "In6.Cu" signal "L7VCC")
		(16 "In7.Cu" signal "L8VCC")
		(18 "In8.Cu" signal "L9GND")
		(20 "In9.Cu" signal "L10")
		(22 "In10.Cu" signal "L11GND")
		(24 "In11.Cu" signal "L12")
		(26 "In12.Cu" signal "L13GND")
		(2 "B.Cu" signal "BOTTOM")
		(9 "F.Adhes" user "F.Adhesive")
		(11 "B.Adhes" user "B.Adhesive")
		(13 "F.Paste" user "Package Geometry/Pastemask Top")
		(15 "B.Paste" user "Package Geometry/Pastemask Bottom")
		(5 "F.SilkS" user "Ref Des/Silkscreen Top")
		(7 "B.SilkS" user "Ref Des/Silkscreen Bottom")
		(1 "F.Mask" user "Board Geometry/Soldermask Top")
		(3 "B.Mask" user "Board Geometry/Soldermask Bottom")
		(17 "Dwgs.User" user "User.Drawings")
		(19 "Cmts.User" user "User.Comments")
		(21 "Eco1.User" user "User.Eco1")
		(23 "Eco2.User" user "User.Eco2")
		(25 "Edge.Cuts" user "Board Geometry/Outline")
		(27 "Margin" user)
		(31 "F.CrtYd" user "Package Geometry/Place Bound Top")
		(29 "B.CrtYd" user "Package Geometry/Place Bound Bottom")
		(35 "F.Fab" user "Ref Des/Assembly Top")
		(33 "B.Fab" user "Ref Des/Assembly Bottom")
	)
	(footprint ""
		(layer "B.Cu")
		(at 365.887 -23.241)
		(property "Reference" "C3T13"
			(at 3.14833 3.937 270)
			(unlocked yes)
			(layer "B.SilkS")
			(effects
				(font
					(size 0.7874 0.5842)
					(thickness 0.1524)
				)
				(justify mirror)
			)
		)
		(property "Value" ""
			(at 0 0 0)
			(layer "B.Fab")
			(effects
				(font
					(size 1.27 1.27)
				)
				(justify mirror)
			)
		)
		(duplicate_pad_numbers_are_jumpers no)
		(fp_line
			(start -2.504948 -1.616456)
			(end -2.504948 1.633728)
			(stroke
				(width 0.1524)
				(type default)
			)
			(layer "B.SilkS")
		)
		(fp_line
			(start -2.504948 1.633728)
			(end -1.6002 1.633728)
			(stroke
				(width 0.1524)
				(type default)
			)
			(layer "B.SilkS")
		)
		(fp_line
			(start -2.286 7.366)
			(end -2.286 1.63195)
			(stroke
				(width 0.1524)
				(type default)
			)
			(layer "B.SilkS")
		)
		(fp_line
			(start -2.286 7.366)
			(end -1.600708 7.366)
			(stroke
				(width 0.1524)
				(type default)
			)
			(layer "B.SilkS")
		)
		(fp_line
			(start -1.6002 -1.616456)
			(end -2.504948 -1.616456)
			(stroke
				(width 0.1524)
				(type default)
			)
			(layer "B.SilkS")
		)
		(fp_line
			(start 1.6002 -1.616456)
			(end 2.563114 -1.616456)
			(stroke
				(width 0.1524)
				(type default)
			)
			(layer "B.SilkS")
		)
		(fp_line
			(start 2.286 7.366)
			(end 1.60147 7.366)
			(stroke
				(width 0.1524)
				(type default)
			)
			(layer "B.SilkS")
		)
		(fp_line
			(start 2.286 7.366)
			(end 2.286 1.632712)
			(stroke
				(width 0.1524)
				(type default)
			)
			(layer "B.SilkS")
		)
		(fp_line
			(start 2.563114 -1.616456)
			(end 2.563114 1.633728)
			(stroke
				(width 0.1524)
				(type default)
			)
			(layer "B.SilkS")
		)
		(fp_line
			(start 2.563114 1.633728)
			(end 1.6002 1.633728)
			(stroke
				(width 0.1524)
				(type default)
			)
			(layer "B.SilkS")
		)
		(fp_rect
			(start 2.286 7.366)
			(end -2.286 -0.254)
			(stroke
				(width 0)
				(type default)
			)
			(fill no)
			(layer "B.CrtYd")
		)
		(fp_line
			(start -2.286 -0.254)
			(end -2.286 7.366)
			(stroke
				(width 0.1)
				(type default)
			)
			(layer "B.Fab")
		)
		(fp_line
			(start -2.286 7.366)
			(end 2.286 7.366)
			(stroke
				(width 0.1)
				(type default)
			)
			(layer "B.Fab")
		)
		(fp_line
			(start 2.286 -0.254)
			(end -2.286 -0.254)
			(stroke
				(width 0.1)
				(type default)
			)
			(layer "B.Fab")
		)
		(fp_line
			(start 2.286 7.366)
			(end 2.286 -0.254)
			(stroke
				(width 0.1)
				(type default)
			)
			(layer "B.Fab")
		)
		(pad "1" smd rect
			(at 0 0 180)
			(size 2.54 3.048)
			(layers "B.Cu" "B.Mask" "B.Paste")
			(net "P12V_STBY")
		)
		(pad "2" smd rect
			(at 0 7.112 180)
			(size 2.54 3.048)
			(layers "B.Cu" "B.Mask" "B.Paste")
			(net "GND")
		)
	)
	(footprint ""
		(layer "B.Cu")
		(at 407.162 -27.94 90)
		(property "Reference" "R25W109"
			(at 0.8382 -0.67818 90)
			(unlocked yes)
			(layer "B.SilkS")
			(effects
				(font
					(size 0.4064 0.254)
					(thickness 0.1524)
				)
				(justify left mirror)
			)
		)
		(property "Value" ""
			(at 0 0 90)
			(layer "B.Fab")
			(effects
				(font
					(size 1.27 1.27)
				)
				(justify mirror)
			)
		)
		(duplicate_pad_numbers_are_jumpers no)
		(fp_poly
			(pts
				(xy 0.2794 -0.1016) (xy -0.2794 -0.1016) (xy -0.2794 0.9906) (xy 0.2794 0.9906)
			)
			(stroke
				(width 0)
				(type default)
			)
			(fill no)
			(layer "B.CrtYd")
		)
		(fp_line
			(start 0.2794 -0.1016)
			(end 0.2794 0.9906)
			(stroke
				(width 0.1)
				(type default)
			)
			(layer "B.Fab")
		)
		(fp_line
			(start -0.2794 -0.1016)
			(end 0.2794 -0.1016)
			(stroke
				(width 0.1)
				(type default)
			)
			(layer "B.Fab")
		)
		(fp_line
			(start 0.2794 0.9906)
			(end -0.2794 0.9906)
			(stroke
				(width 0.1)
				(type default)
			)
			(layer "B.Fab")
		)
		(fp_line
			(start -0.2794 0.9906)
			(end -0.2794 -0.1016)
			(stroke
				(width 0.1)
				(type default)
			)
			(layer "B.Fab")
		)
		(pad "1" smd rect
			(at 0 0 270)
			(size 0.508 0.508)
			(layers "B.Cu" "B.Mask" "B.Paste")
			(net "P3V3_STBY")
		)
		(pad "2" smd rect
			(at 0 0.889 270)
			(size 0.508 0.508)
			(layers "B.Cu" "B.Mask" "B.Paste")
			(net "TP_RGMII2TXD3_GPIOU3")
		)
		(zone
			(layer "B.Cu")
			(hatch none 0.5)
			(connect_pads
				(clearance 0)
			)
			(min_thickness 0.25)
			(keepout
				(tracks allowed)
				(vias not_allowed)
				(pads allowed)
				(copperpour not_allowed)
				(footprints allowed)
			)
			(placement
				(enabled no)
				(sheetname "")
			)
			(fill
				(thermal_gap 0.5)
				(thermal_bridge_width 0.5)
				(island_removal_mode 0)
			)
			(polygon
				(pts
					(xy 407.416 -28.194) (xy 407.416 -27.686) (xy 407.797 -27.686) (xy 407.797 -28.194)
				)
			)
		)
		(zone
			(layer "B.Cu")
			(hatch none 0.5)
			(connect_pads
				(clearance 0)
			)
			(min_thickness 0.25)
			(keepout
				(tracks not_allowed)
				(vias allowed)
				(pads allowed)
				(copperpour not_allowed)
				(footprints allowed)
			)
			(placement
				(enabled no)
				(sheetname "")
			)
			(fill
				(thermal_gap 0.5)
				(thermal_bridge_width 0.5)
				(island_removal_mode 0)
			)
			(polygon
				(pts
					(xy 407.797 -28.194) (xy 407.797 -27.686) (xy 407.416 -27.686) (xy 407.416 -28.194)
				)
			)
		)
	)
	(footprint ""
		(layer "B.Cu")
		(at 392.498834 -107.356148)
		(property "Reference" "R2N4"
			(at 0 0 0)
			(layer "B.SilkS")
			(hide yes)
			(effects
				(font
					(size 1.27 1.27)
				)
				(justify mirror)
			)
		)
		(property "Value" ""
			(at 0 0 0)
			(layer "B.Fab")
			(effects
				(font
					(size 1.27 1.27)
				)
				(justify mirror)
			)
		)
		(duplicate_pad_numbers_are_jumpers no)
		(fp_poly
			(pts
				(xy 0.2794 -0.1016) (xy -0.2794 -0.1016) (xy -0.2794 0.9906) (xy 0.2794 0.9906)
			)
			(stroke
				(width 0)
				(type default)
			)
			(fill no)
			(layer "B.CrtYd")
		)
		(fp_line
			(start -0.2794 -0.1016)
			(end 0.2794 -0.1016)
			(stroke
				(width 0.1)
				(type default)
			)
			(layer "B.Fab")
		)
		(fp_line
			(start -0.2794 0.9906)
			(end -0.2794 -0.1016)
			(stroke
				(width 0.1)
				(type default)
			)
			(layer "B.Fab")
		)
		(fp_line
			(start 0.2794 -0.1016)
			(end 0.2794 0.9906)
			(stroke
				(width 0.1)
				(type default)
			)
			(layer "B.Fab")
		)
		(fp_line
			(start 0.2794 0.9906)
			(end -0.2794 0.9906)
			(stroke
				(width 0.1)
				(type default)
			)
			(layer "B.Fab")
		)
		(pad "1" smd rect
			(at 0 0 180)
			(size 0.508 0.508)
			(layers "B.Cu" "B.Mask" "B.Paste")
			(net "P1V05_PCH_STBY_KR_PLL")
		)
		(pad "2" smd rect
			(at 0 0.889 180)
			(size 0.508 0.508)
			(layers "B.Cu" "B.Mask" "B.Paste")
			(net "A_KR0_RBIAS")
		)
		(zone
			(layer "B.Cu")
			(hatch none 0.5)
			(connect_pads
				(clearance 0)
			)
			(min_thickness 0.25)
			(keepout
				(tracks allowed)
				(vias not_allowed)
				(pads allowed)
				(copperpour not_allowed)
				(footprints allowed)
			)
			(placement
				(enabled no)
				(sheetname "")
			)
			(fill
				(thermal_gap 0.5)
				(thermal_bridge_width 0.5)
				(island_removal_mode 0)
			)
			(polygon
				(pts
					(xy 392.752834 -107.102148) (xy 392.244834 -107.102148) (xy 392.244834 -106.721148) (xy 392.752834 -106.721148)
				)
			)
		)
		(zone
			(layer "B.Cu")
			(hatch none 0.5)
			(connect_pads
				(clearance 0)
			)
			(min_thickness 0.25)
			(keepout
				(tracks not_allowed)
				(vias allowed)
				(pads allowed)
				(copperpour not_allowed)
				(footprints allowed)
			)
			(placement
				(enabled no)
				(sheetname "")
			)
			(fill
				(thermal_gap 0.5)
				(thermal_bridge_width 0.5)
				(island_removal_mode 0)
			)
			(polygon
				(pts
					(xy 392.752834 -106.721148) (xy 392.244834 -106.721148) (xy 392.244834 -107.102148) (xy 392.752834 -107.102148)
				)
			)
		)
	)
	(footprint ""
		(layer "B.Cu")
		(at 373.944642 -72.295512 180)
		(property "Reference" "C2R5"
			(at 0 0 0)
			(layer "B.SilkS")
			(hide yes)
			(effects
				(font
					(size 1.27 1.27)
				)
				(justify mirror)
			)
		)
		(property "Value" ""
			(at 0 0 0)
			(layer "B.Fab")
			(effects
				(font
					(size 1.27 1.27)
				)
				(justify mirror)
			)
		)
		(duplicate_pad_numbers_are_jumpers no)
		(fp_rect
			(start 0.2794 0.9144)
			(end -0.2794 -0.1143)
			(stroke
				(width 0)
				(type default)
			)
			(fill no)
			(layer "B.CrtYd")
		)
		(fp_line
			(start 0.2794 0.9144)
			(end 0.2794 -0.1143)
			(stroke
				(width 0.1)
				(type default)
			)
			(layer "B.Fab")
		)
		(fp_line
			(start 0.2794 -0.1143)
			(end -0.2794 -0.1143)
			(stroke
				(width 0.1)
				(type default)
			)
			(layer "B.Fab")
		)
		(fp_line
			(start -0.2794 0.9144)
			(end 0.2794 0.9144)
			(stroke
				(width 0.1)
				(type default)
			)
			(layer "B.Fab")
		)
		(fp_line
			(start -0.2794 -0.1143)
			(end -0.2794 0.9144)
			(stroke
				(width 0.1)
				(type default)
			)
			(layer "B.Fab")
		)
		(pad "1" smd custom
			(at 0 0 90)
			(size 0.10414 0.10414)
			(layers "B.Cu" "B.Mask" "B.Paste")
			(net "P3V3_STBY")
			(options
				(clearance outline)
				(anchor circle)
			)
			(primitives
				(gr_poly
					(pts
						(xy -0.20828 -0.08636) (xy -0.20828 0.08636) (xy -0.08636 0.20828) (xy 0.086614 0.20828) (xy 0.20828 0.086614)
						(xy 0.20828 -0.08636) (xy 0.08636 -0.20828) (xy -0.08636 -0.20828)
					)
					(width 0)
					(fill yes)
				)
			)
		)
		(pad "2" smd custom
			(at 0 0.8001 90)
			(size 0.10414 0.10414)
			(layers "B.Cu" "B.Mask" "B.Paste")
			(net "GND")
			(options
				(clearance outline)
				(anchor circle)
			)
			(primitives
				(gr_poly
					(pts
						(xy -0.20828 -0.08636) (xy -0.20828 0.08636) (xy -0.08636 0.20828) (xy 0.086614 0.20828) (xy 0.20828 0.086614)
						(xy 0.20828 -0.08636) (xy 0.08636 -0.20828) (xy -0.08636 -0.20828)
					)
					(width 0)
					(fill yes)
				)
			)
		)
		(zone
			(layer "B.Cu")
			(hatch none 0.5)
			(connect_pads
				(clearance 0)
			)
			(min_thickness 0.25)
			(keepout
				(tracks not_allowed)
				(vias allowed)
				(pads allowed)
				(copperpour not_allowed)
				(footprints allowed)
			)
			(placement
				(enabled no)
				(sheetname "")
			)
			(fill
				(thermal_gap 0.5)
				(thermal_bridge_width 0.5)
				(island_removal_mode 0)
			)
			(polygon
				(pts
					(xy 373.857012 -72.505062) (xy 373.857012 -72.886062) (xy 374.032272 -72.886062) (xy 374.032526 -72.505062)
				)
			)
		)
		(zone
			(layer "B.Cu")
			(hatch none 0.5)
			(connect_pads
				(clearance 0)
			)
			(min_thickness 0.25)
			(keepout
				(tracks allowed)
				(vias not_allowed)
				(pads allowed)
				(copperpour not_allowed)
				(footprints allowed)
			)
			(placement
				(enabled no)
				(sheetname "")
			)
			(fill
				(thermal_gap 0.5)
				(thermal_bridge_width 0.5)
				(island_removal_mode 0)
			)
			(polygon
				(pts
					(xy 373.857012 -72.505062) (xy 373.857012 -72.886062) (xy 374.032272 -72.886062) (xy 374.032526 -72.505062)
				)
			)
		)
	)
	(footprint ""
		(layer "B.Cu")
		(at 408.8765 -4.572 90)
		(property "Reference" "R8D37"
			(at 0 0 90)
			(layer "B.SilkS")
			(hide yes)
			(effects
				(font
					(size 1.27 1.27)
				)
				(justify mirror)
			)
		)
		(property "Value" ""
			(at 0 0 90)
			(layer "B.Fab")
			(effects
				(font
					(size 1.27 1.27)
				)
				(justify mirror)
			)
		)
		(duplicate_pad_numbers_are_jumpers no)
		(fp_poly
			(pts
				(xy 0.2794 -0.1016) (xy -0.2794 -0.1016) (xy -0.2794 0.9906) (xy 0.2794 0.9906)
			)
			(stroke
				(width 0)
				(type default)
			)
			(fill no)
			(layer "B.CrtYd")
		)
		(fp_line
			(start 0.2794 -0.1016)
			(end 0.2794 0.9906)
			(stroke
				(width 0.1)
				(type default)
			)
			(layer "B.Fab")
		)
		(fp_line
			(start -0.2794 -0.1016)
			(end 0.2794 -0.1016)
			(stroke
				(width 0.1)
				(type default)
			)
			(layer "B.Fab")
		)
		(fp_line
			(start 0.2794 0.9906)
			(end -0.2794 0.9906)
			(stroke
				(width 0.1)
				(type default)
			)
			(layer "B.Fab")
		)
		(fp_line
			(start -0.2794 0.9906)
			(end -0.2794 -0.1016)
			(stroke
				(width 0.1)
				(type default)
			)
			(layer "B.Fab")
		)
		(pad "1" smd rect
			(at 0 0 270)
			(size 0.508 0.508)
			(layers "B.Cu" "B.Mask" "B.Paste")
			(net "A_PG_P5V")
		)
		(pad "2" smd rect
			(at 0 0.889 270)
			(size 0.508 0.508)
			(layers "B.Cu" "B.Mask" "B.Paste")
			(net "GND")
		)
		(zone
			(layer "B.Cu")
			(hatch none 0.5)
			(connect_pads
				(clearance 0)
			)
			(min_thickness 0.25)
			(keepout
				(tracks allowed)
				(vias not_allowed)
				(pads allowed)
				(copperpour not_allowed)
				(footprints allowed)
			)
			(placement
				(enabled no)
				(sheetname "")
			)
			(fill
				(thermal_gap 0.5)
				(thermal_bridge_width 0.5)
				(island_removal_mode 0)
			)
			(polygon
				(pts
					(xy 409.1305 -4.826) (xy 409.1305 -4.318) (xy 409.5115 -4.318) (xy 409.5115 -4.826)
				)
			)
		)
		(zone
			(layer "B.Cu")
			(hatch none 0.5)
			(connect_pads
				(clearance 0)
			)
			(min_thickness 0.25)
			(keepout
				(tracks not_allowed)
				(vias allowed)
				(pads allowed)
				(copperpour not_allowed)
				(footprints allowed)
			)
			(placement
				(enabled no)
				(sheetname "")
			)
			(fill
				(thermal_gap 0.5)
				(thermal_bridge_width 0.5)
				(island_removal_mode 0)
			)
			(polygon
				(pts
					(xy 409.5115 -4.826) (xy 409.5115 -4.318) (xy 409.1305 -4.318) (xy 409.1305 -4.826)
				)
			)
		)
	)
	(footprint ""
		(layer "B.Cu")
		(at 162.7886 -76.708 90)
		(property "Reference" "R7P12"
			(at 0 0 90)
			(layer "B.SilkS")
			(hide yes)
			(effects
				(font
					(size 1.27 1.27)
				)
				(justify mirror)
			)
		)
		(property "Value" ""
			(at 0 0 90)
			(layer "B.Fab")
			(effects
				(font
					(size 1.27 1.27)
				)
				(justify mirror)
			)
		)
		(duplicate_pad_numbers_are_jumpers no)
		(fp_poly
			(pts
				(xy 0.2794 -0.1016) (xy -0.2794 -0.1016) (xy -0.2794 0.9906) (xy 0.2794 0.9906)
			)
			(stroke
				(width 0)
				(type default)
			)
			(fill no)
			(layer "B.CrtYd")
		)
		(fp_line
			(start 0.2794 -0.1016)
			(end 0.2794 0.9906)
			(stroke
				(width 0.1)
				(type default)
			)
			(layer "B.Fab")
		)
		(fp_line
			(start -0.2794 -0.1016)
			(end 0.2794 -0.1016)
			(stroke
				(width 0.1)
				(type default)
			)
			(layer "B.Fab")
		)
		(fp_line
			(start 0.2794 0.9906)
			(end -0.2794 0.9906)
			(stroke
				(width 0.1)
				(type default)
			)
			(layer "B.Fab")
		)
		(fp_line
			(start -0.2794 0.9906)
			(end -0.2794 -0.1016)
			(stroke
				(width 0.1)
				(type default)
			)
			(layer "B.Fab")
		)
		(pad "1" smd rect
			(at 0 0 270)
			(size 0.508 0.508)
			(layers "B.Cu" "B.Mask" "B.Paste")
			(net "CLK_100M_CPU1_RC_REFCLK1_DN")
		)
		(pad "2" smd rect
			(at 0 0.889 270)
			(size 0.508 0.508)
			(layers "B.Cu" "B.Mask" "B.Paste")
			(net "GND")
		)
		(zone
			(layer "B.Cu")
			(hatch none 0.5)
			(connect_pads
				(clearance 0)
			)
			(min_thickness 0.25)
			(keepout
				(tracks allowed)
				(vias not_allowed)
				(pads allowed)
				(copperpour not_allowed)
				(footprints allowed)
			)
			(placement
				(enabled no)
				(sheetname "")
			)
			(fill
				(thermal_gap 0.5)
				(thermal_bridge_width 0.5)
				(island_removal_mode 0)
			)
			(polygon
				(pts
					(xy 163.0426 -76.962) (xy 163.0426 -76.454) (xy 163.4236 -76.454) (xy 163.4236 -76.962)
				)
			)
		)
		(zone
			(layer "B.Cu")
			(hatch none 0.5)
			(connect_pads
				(clearance 0)
			)
			(min_thickness 0.25)
			(keepout
				(tracks not_allowed)
				(vias allowed)
				(pads allowed)
				(copperpour not_allowed)
				(footprints allowed)
			)
			(placement
				(enabled no)
				(sheetname "")
			)
			(fill
				(thermal_gap 0.5)
				(thermal_bridge_width 0.5)
				(island_removal_mode 0)
			)
			(polygon
				(pts
					(xy 163.4236 -76.962) (xy 163.4236 -76.454) (xy 163.0426 -76.454) (xy 163.0426 -76.962)
				)
			)
		)
	)
	(footprint ""
		(layer "B.Cu")
		(at 372.169436 -47.436532)
		(property "Reference" "R2T68"
			(at 0 0 0)
			(layer "B.SilkS")
			(hide yes)
			(effects
				(font
					(size 1.27 1.27)
				)
				(justify mirror)
			)
		)
		(property "Value" ""
			(at 0 0 0)
			(layer "B.Fab")
			(effects
				(font
					(size 1.27 1.27)
				)
				(justify mirror)
			)
		)
		(duplicate_pad_numbers_are_jumpers no)
		(fp_poly
			(pts
				(xy 0.2794 -0.1016) (xy -0.2794 -0.1016) (xy -0.2794 0.9906) (xy 0.2794 0.9906)
			)
			(stroke
				(width 0)
				(type default)
			)
			(fill no)
			(layer "B.CrtYd")
		)
		(fp_line
			(start -0.2794 -0.1016)
			(end 0.2794 -0.1016)
			(stroke
				(width 0.1)
				(type default)
			)
			(layer "B.Fab")
		)
		(fp_line
			(start -0.2794 0.9906)
			(end -0.2794 -0.1016)
			(stroke
				(width 0.1)
				(type default)
			)
			(layer "B.Fab")
		)
		(fp_line
			(start 0.2794 -0.1016)
			(end 0.2794 0.9906)
			(stroke
				(width 0.1)
				(type default)
			)
			(layer "B.Fab")
		)
		(fp_line
			(start 0.2794 0.9906)
			(end -0.2794 0.9906)
			(stroke
				(width 0.1)
				(type default)
			)
			(layer "B.Fab")
		)
		(pad "1" smd rect
			(at 0 0 180)
			(size 0.508 0.508)
			(layers "B.Cu" "B.Mask" "B.Paste")
			(net "H_CPU1_PROCHOT_G_N")
		)
		(pad "2" smd rect
			(at 0 0.889 180)
			(size 0.508 0.508)
			(layers "B.Cu" "B.Mask" "B.Paste")
			(net "H_CPU1_PROCHOT_G_R_N")
		)
		(zone
			(layer "B.Cu")
			(hatch none 0.5)
			(connect_pads
				(clearance 0)
			)
			(min_thickness 0.25)
			(keepout
				(tracks allowed)
				(vias not_allowed)
				(pads allowed)
				(copperpour not_allowed)
				(footprints allowed)
			)
			(placement
				(enabled no)
				(sheetname "")
			)
			(fill
				(thermal_gap 0.5)
				(thermal_bridge_width 0.5)
				(island_removal_mode 0)
			)
			(polygon
				(pts
					(xy 372.423436 -47.182532) (xy 371.915436 -47.182532) (xy 371.915436 -46.801532) (xy 372.423436 -46.801532)
				)
			)
		)
		(zone
			(layer "B.Cu")
			(hatch none 0.5)
			(connect_pads
				(clearance 0)
			)
			(min_thickness 0.25)
			(keepout
				(tracks not_allowed)
				(vias allowed)
				(pads allowed)
				(copperpour not_allowed)
				(footprints allowed)
			)
			(placement
				(enabled no)
				(sheetname "")
			)
			(fill
				(thermal_gap 0.5)
				(thermal_bridge_width 0.5)
				(island_removal_mode 0)
			)
			(polygon
				(pts
					(xy 372.423436 -46.801532) (xy 371.915436 -46.801532) (xy 371.915436 -47.182532) (xy 372.423436 -47.182532)
				)
			)
		)
	)
)
